FILE_TYPE=LIBRARY_PARTS;
primitive 'TTL08','TTL08_SM','TTL08_SMLF';
  pin
    'Y'<0>:
      OUTPUT_LOAD='(20.0,-1.0)';
      PIN_NUMBER='(11,8,6,3)';
    'B'<0>:
      INPUT_LOAD='(-0.6,0.02)';
      PIN_NUMBER='(13,10,5,2)';
      PIN_GROUP='1';
    'A'<0>:
      INPUT_LOAD='(-0.6,0.02)';
      PIN_NUMBER='(12,9,4,1)';
      PIN_GROUP='1';
  end_pin;
  body
    POWER_PINS='(VCC:14)';
    POWER_PINS='(GND:7)';
    PHYS_DES_PREFIX='U';
    PART_NAME='TTL08';
  end_body;
end_primitive;
primitive 'TTL08_SMTHLF','TTL08_QFN15';
  pin
    'Y'<0>:
      OUTPUT_LOAD='(20.0,-1.0)';
      PIN_NUMBER='(11,8,6,3)';
    'B'<0>:
      INPUT_LOAD='(-0.6,0.02)';
      PIN_NUMBER='(13,10,5,2)';
      PIN_GROUP='1';
    'A'<0>:
      INPUT_LOAD='(-0.6,0.02)';
      PIN_NUMBER='(12,9,4,1)';
      PIN_GROUP='1';
  end_pin;
  body
    POWER_PINS='(VCC:14)';
    POWER_PINS='(GND:7)';
    POWER_PINS='(TH:15)';
    PHYS_DES_PREFIX='EU';
    PART_NAME='TTL08';
  end_body;
end_primitive;
END.
